# BASEBOARD_FAB2 (Tioga Pass) — schematic netlist excerpt (pin names and nets, part order shuffled) for the footprints in the layout excerpt that follows; sources: Cadence DE-HDL packaged netlist, KiCad conversion of Wiwynn_Tioga_Pass_MB.brd

C1D25  CAP  1.0UF 16V 10% X6S  pkg 0402  page 199 : A = P12V_HSC_VCC ; B = AGND_HSC
R25W30  RES  2.7K 1% CHIP  pkg 0402  page 151 : A = BMC_M_MALERT_N ; B = P1V2_AUX_BMC
L4D1  IND-120NH-30-GP  pkg DISCRET-GB2  page 203 : S = VR_PVCCIN_CPU0_PHASE4 ; F = PVCCIN_CPU0

(kicad_pcb
	(version 20260206)
	(generator "pcbnew")
	(generator_version "10.0")
	(general
		(thickness 1.6)
		(legacy_teardrops no)
	)
	(paper "A4")
	(title_block
		(title "Wiwynn_Tioga_Pass_MB.brd")
		(comment 1 "Tioga Pass / footprints 1762-1764 of 4770")
	)
	(layers
		(0 "F.Cu" signal "TOP")
		(4 "In1.Cu" signal "L2GND")
		(6 "In2.Cu" signal "L3")
		(8 "In3.Cu" signal "L4GND")
		(10 "In4.Cu" signal "L5")
		(12 "In5.Cu" signal "L6GND")
		(14 "In6.Cu" signal "L7VCC")
		(16 "In7.Cu" signal "L8VCC")
		(18 "In8.Cu" signal "L9GND")
		(20 "In9.Cu" signal "L10")
		(22 "In10.Cu" signal "L11GND")
		(24 "In11.Cu" signal "L12")
		(26 "In12.Cu" signal "L13GND")
		(2 "B.Cu" signal "BOTTOM")
		(9 "F.Adhes" user "F.Adhesive")
		(11 "B.Adhes" user "B.Adhesive")
		(13 "F.Paste" user "Package Geometry/Pastemask Top")
		(15 "B.Paste" user "Package Geometry/Pastemask Bottom")
		(5 "F.SilkS" user "Ref Des/Silkscreen Top")
		(7 "B.SilkS" user "Ref Des/Silkscreen Bottom")
		(1 "F.Mask" user "Board Geometry/Soldermask Top")
		(3 "B.Mask" user "Board Geometry/Soldermask Bottom")
		(17 "Dwgs.User" user "User.Drawings")
		(19 "Cmts.User" user "User.Comments")
		(21 "Eco1.User" user "User.Eco1")
		(23 "Eco2.User" user "User.Eco2")
		(25 "Edge.Cuts" user "Board Geometry/Outline")
		(27 "Margin" user)
		(31 "F.CrtYd" user "Package Geometry/Place Bound Top")
		(29 "B.CrtYd" user "Package Geometry/Place Bound Bottom")
		(35 "F.Fab" user "Ref Des/Assembly Top")
		(33 "B.Fab" user "Ref Des/Assembly Bottom")
	)
	(footprint ""
		(layer "F.Cu")
		(at 435.388766 -43.086274 180)
		(property "Reference" "R25W30"
			(at -0.8382 -0.67818 180)
			(unlocked yes)
			(layer "F.SilkS")
			(effects
				(font
					(size 0.4064 0.254)
					(thickness 0.1524)
				)
				(justify left)
			)
		)
		(property "Value" ""
			(at 0 0 180)
			(layer "F.Fab")
			(effects
				(font
					(size 1.27 1.27)
				)
			)
		)
		(duplicate_pad_numbers_are_jumpers no)
		(fp_poly
			(pts
				(xy -0.2794 -0.1016) (xy 0.2794 -0.1016) (xy 0.2794 0.9906) (xy -0.2794 0.9906)
			)
			(stroke
				(width 0)
				(type default)
			)
			(fill no)
			(layer "F.CrtYd")
		)
		(fp_line
			(start 0.2794 0.9906)
			(end 0.2794 -0.1016)
			(stroke
				(width 0.1)
				(type default)
			)
			(layer "F.Fab")
		)
		(fp_line
			(start 0.2794 -0.1016)
			(end -0.2794 -0.1016)
			(stroke
				(width 0.1)
				(type default)
			)
			(layer "F.Fab")
		)
		(fp_line
			(start -0.2794 0.9906)
			(end 0.2794 0.9906)
			(stroke
				(width 0.1)
				(type default)
			)
			(layer "F.Fab")
		)
		(fp_line
			(start -0.2794 -0.1016)
			(end -0.2794 0.9906)
			(stroke
				(width 0.1)
				(type default)
			)
			(layer "F.Fab")
		)
		(pad "1" smd rect
			(at 0 0 180)
			(size 0.508 0.508)
			(layers "F.Cu" "F.Mask" "F.Paste")
			(net "BMC_M_MALERT_N")
		)
		(pad "2" smd rect
			(at 0 0.889 180)
			(size 0.508 0.508)
			(layers "F.Cu" "F.Mask" "F.Paste")
			(net "P1V2_AUX_BMC")
		)
		(zone
			(layer "F.Cu")
			(hatch none 0.5)
			(connect_pads
				(clearance 0)
			)
			(min_thickness 0.25)
			(keepout
				(tracks not_allowed)
				(vias allowed)
				(pads allowed)
				(copperpour not_allowed)
				(footprints allowed)
			)
			(placement
				(enabled no)
				(sheetname "")
			)
			(fill
				(thermal_gap 0.5)
				(thermal_bridge_width 0.5)
				(island_removal_mode 0)
			)
			(polygon
				(pts
					(xy 435.642766 -43.721274) (xy 435.134766 -43.721274) (xy 435.134766 -43.340274) (xy 435.642766 -43.340274)
				)
			)
		)
		(zone
			(layer "F.Cu")
			(hatch none 0.5)
			(connect_pads
				(clearance 0)
			)
			(min_thickness 0.25)
			(keepout
				(tracks allowed)
				(vias not_allowed)
				(pads allowed)
				(copperpour not_allowed)
				(footprints allowed)
			)
			(placement
				(enabled no)
				(sheetname "")
			)
			(fill
				(thermal_gap 0.5)
				(thermal_bridge_width 0.5)
				(island_removal_mode 0)
			)
			(polygon
				(pts
					(xy 435.642766 -43.340274) (xy 435.134766 -43.340274) (xy 435.134766 -43.721274) (xy 435.642766 -43.721274)
				)
			)
		)
	)
	(footprint ""
		(layer "F.Cu")
		(at 18.669 -70.866)
		(property "Reference" "C1D25"
			(at 0 0 0)
			(layer "F.SilkS")
			(hide yes)
			(effects
				(font
					(size 1.27 1.27)
				)
			)
		)
		(property "Value" ""
			(at 0 0 0)
			(layer "F.Fab")
			(effects
				(font
					(size 1.27 1.27)
				)
			)
		)
		(duplicate_pad_numbers_are_jumpers no)
		(fp_poly
			(pts
				(xy 0.3048 -0.1016) (xy 0.3048 0.9906) (xy -0.3048 0.9906) (xy -0.3048 -0.1016)
			)
			(stroke
				(width 0)
				(type default)
			)
			(fill no)
			(layer "F.CrtYd")
		)
		(fp_line
			(start -0.3048 -0.1016)
			(end -0.3048 0.9906)
			(stroke
				(width 0.1)
				(type default)
			)
			(layer "F.Fab")
		)
		(fp_line
			(start -0.3048 0.9906)
			(end 0.3048 0.9906)
			(stroke
				(width 0.1)
				(type default)
			)
			(layer "F.Fab")
		)
		(fp_line
			(start 0.3048 -0.1016)
			(end -0.3048 -0.1016)
			(stroke
				(width 0.1)
				(type default)
			)
			(layer "F.Fab")
		)
		(fp_line
			(start 0.3048 0.9906)
			(end 0.3048 -0.1016)
			(stroke
				(width 0.1)
				(type default)
			)
			(layer "F.Fab")
		)
		(pad "1" smd rect
			(at 0 0)
			(size 0.508 0.508)
			(layers "F.Cu" "F.Mask" "F.Paste")
			(net "P12V_HSC_VCC")
		)
		(pad "2" smd rect
			(at 0 0.889)
			(size 0.508 0.508)
			(layers "F.Cu" "F.Mask" "F.Paste")
			(net "AGND_HSC")
		)
		(zone
			(layer "F.Cu")
			(hatch none 0.5)
			(connect_pads
				(clearance 0)
			)
			(min_thickness 0.25)
			(keepout
				(tracks allowed)
				(vias not_allowed)
				(pads allowed)
				(copperpour not_allowed)
				(footprints allowed)
			)
			(placement
				(enabled no)
				(sheetname "")
			)
			(fill
				(thermal_gap 0.5)
				(thermal_bridge_width 0.5)
				(island_removal_mode 0)
			)
			(polygon
				(pts
					(xy 18.415 -70.612) (xy 18.923 -70.612) (xy 18.923 -70.231) (xy 18.415 -70.231)
				)
			)
		)
		(zone
			(layer "F.Cu")
			(hatch none 0.5)
			(connect_pads
				(clearance 0)
			)
			(min_thickness 0.25)
			(keepout
				(tracks not_allowed)
				(vias allowed)
				(pads allowed)
				(copperpour not_allowed)
				(footprints allowed)
			)
			(placement
				(enabled no)
				(sheetname "")
			)
			(fill
				(thermal_gap 0.5)
				(thermal_bridge_width 0.5)
				(island_removal_mode 0)
			)
			(polygon
				(pts
					(xy 18.415 -70.231) (xy 18.923 -70.231) (xy 18.923 -70.612) (xy 18.415 -70.612)
				)
			)
		)
	)
	(footprint ""
		(layer "F.Cu")
		(at 205.036928 -81.415382)
		(property "Reference" "L4D1"
			(at 3.378708 -4.251706 0)
			(unlocked yes)
			(layer "F.SilkS")
			(effects
				(font
					(size 0.4064 0.254)
					(thickness 0.1524)
				)
			)
		)
		(property "Value" ""
			(at 0 0 0)
			(layer "F.Fab")
			(effects
				(font
					(size 1.27 1.27)
				)
			)
		)
		(duplicate_pad_numbers_are_jumpers no)
		(fp_line
			(start -1.1303 -3.199892)
			(end 8.3693 -3.199892)
			(stroke
				(width 0.1524)
				(type default)
			)
			(layer "F.SilkS")
		)
		(fp_line
			(start -1.1303 -1.6637)
			(end -1.1303 -3.199892)
			(stroke
				(width 0.1524)
				(type default)
			)
			(layer "F.SilkS")
		)
		(fp_line
			(start -1.1303 3.199892)
			(end -1.1303 1.6637)
			(stroke
				(width 0.1524)
				(type default)
			)
			(layer "F.SilkS")
		)
		(fp_line
			(start 8.3693 -3.199892)
			(end 8.3693 -1.6637)
			(stroke
				(width 0.1524)
				(type default)
			)
			(layer "F.SilkS")
		)
		(fp_line
			(start 8.3693 1.6637)
			(end 8.3693 3.199892)
			(stroke
				(width 0.1524)
				(type default)
			)
			(layer "F.SilkS")
		)
		(fp_line
			(start 8.3693 3.199892)
			(end -1.1303 3.199892)
			(stroke
				(width 0.1524)
				(type default)
			)
			(layer "F.SilkS")
		)
		(fp_rect
			(start -1.1303 3.199892)
			(end 8.3693 -3.199892)
			(stroke
				(width 0)
				(type default)
			)
			(fill no)
			(layer "F.CrtYd")
		)
		(fp_line
			(start -1.1303 -3.199892)
			(end 8.3693 -3.199892)
			(stroke
				(width 0.1)
				(type default)
			)
			(layer "F.Fab")
		)
		(fp_line
			(start -1.1303 3.199892)
			(end -1.1303 -3.199892)
			(stroke
				(width 0.1)
				(type default)
			)
			(layer "F.Fab")
		)
		(fp_line
			(start 8.3693 -3.199892)
			(end 8.3693 3.199892)
			(stroke
				(width 0.1)
				(type default)
			)
			(layer "F.Fab")
		)
		(fp_line
			(start 8.3693 3.199892)
			(end -1.1303 3.199892)
			(stroke
				(width 0.1)
				(type default)
			)
			(layer "F.Fab")
		)
		(pad "1" smd rect
			(at 0 0)
			(size 3.683 2.667)
			(layers "F.Cu" "F.Mask" "F.Paste")
			(net "VR_PVCCIN_CPU0_PHASE4")
		)
		(pad "2" smd rect
			(at 7.239 0)
			(size 3.683 2.667)
			(layers "F.Cu" "F.Mask" "F.Paste")
			(net "PVCCIN_CPU0")
		)
	)
)
